(kicad_pcb
	(version 20241229)
	(generator "pcbnew")
	(generator_version "9.0")
	(general
		(thickness 1.711)
		(legacy_teardrops no)
	)
	(paper "A4")
	(title_block
		(title "Antmicro Baseboard for Jetson AGX Thor")
		(date "2026-02-18")
		(rev "1.1.0")
		(company "Antmicro Ltd")
		(comment 1 "www.antmicro.com")
		(comment 9 "footprints 399-402 of 1170")
	)
	(layers
		(0 "F.Cu" signal)
		(4 "In1.Cu" signal)
		(6 "In2.Cu" signal)
		(8 "In3.Cu" signal)
		(10 "In4.Cu" jumper)
		(12 "In5.Cu" signal)
		(14 "In6.Cu" signal)
		(16 "In7.Cu" signal)
		(18 "In8.Cu" signal)
		(2 "B.Cu" signal)
		(9 "F.Adhes" user "F.Adhesive")
		(11 "B.Adhes" user "B.Adhesive")
		(13 "F.Paste" user)
		(15 "B.Paste" user)
		(5 "F.SilkS" user "F.Silkscreen")
		(7 "B.SilkS" user "B.Silkscreen")
		(1 "F.Mask" user)
		(3 "B.Mask" user)
		(17 "Dwgs.User" user "User.Drawings")
		(19 "Cmts.User" user "User.Comments")
		(21 "Eco1.User" user "User.Eco1")
		(23 "Eco2.User" user "User.Eco2")
		(25 "Edge.Cuts" user)
		(27 "Margin" user)
		(31 "F.CrtYd" user "F.Courtyard")
		(29 "B.CrtYd" user "B.Courtyard")
		(35 "F.Fab" user)
		(33 "B.Fab" user)
	)
	(footprint "antmicro-footprints:SOT-23-8"
		(layer "F.Cu")
		(at 171.49 121.701 -90)
		(descr "http://www.ti.com/lit/ds/symlink/ina219.pdf")
		(property "Reference" "U50"
			(at 1.675 -2.759468 90)
			(layer "F.SilkS")
			(effects
				(font
					(size 0.7 0.7)
					(thickness 0.15)
				)
				(justify left bottom)
			)
		)
		(property "Value" "INA219AIDCNR"
			(at -2.925 2.8 90)
			(layer "F.Fab")
			(effects
				(font
					(size 0.7 0.7)
					(thickness 0.15)
				)
				(justify right top)
			)
		)
		(property "Datasheet" "https://www.ti.com/lit/ds/symlink/ina219.pdf?ts=1713856455637&ref_url=https%253A%252F%252Fwww.mouser.es%252F"
			(at 0 0 90)
			(layer "F.Fab")
			(hide yes)
			(effects
				(font
					(size 1.27 1.27)
					(thickness 0.15)
				)
			)
		)
		(property "Description" "Zerø-Drift, Bidirectional Current/Power Monitor With I2C Interface"
			(at 0 0 90)
			(layer "F.Fab")
			(hide yes)
			(effects
				(font
					(size 1.27 1.27)
					(thickness 0.15)
				)
			)
		)
		(property "Manufacturer" "Texas Instruments"
			(at 0 0 270)
			(unlocked yes)
			(layer "F.Fab")
			(hide yes)
			(effects
				(font
					(size 1 1)
					(thickness 0.15)
				)
			)
		)
		(property "MPN" "INA219AIDCNR"
			(at 0 0 270)
			(unlocked yes)
			(layer "F.Fab")
			(hide yes)
			(effects
				(font
					(size 1 1)
					(thickness 0.15)
				)
			)
		)
		(property "Author" "Antmicro"
			(at 0 0 270)
			(unlocked yes)
			(layer "F.Fab")
			(hide yes)
			(effects
				(font
					(size 1 1)
					(thickness 0.15)
				)
			)
		)
		(property "License" "Apache-2.0"
			(at 0 0 270)
			(unlocked yes)
			(layer "F.Fab")
			(hide yes)
			(effects
				(font
					(size 1 1)
					(thickness 0.15)
				)
			)
		)
		(sheetname "/DCDC/")
		(sheetfile "dcdc.kicad_sch")
		(attr smd)
		(fp_line
			(start -0.987 1.6)
			(end -0.987 1.324)
			(stroke
				(width 0.15)
				(type solid)
			)
			(layer "F.SilkS")
		)
		(fp_line
			(start -0.613 1.6)
			(end -0.987 1.6)
			(stroke
				(width 0.15)
				(type solid)
			)
			(layer "F.SilkS")
		)
		(fp_line
			(start 1 1.6)
			(end 0.6 1.6)
			(stroke
				(width 0.15)
				(type solid)
			)
			(layer "F.SilkS")
		)
		(fp_line
			(start 1 1.3)
			(end 1 1.6)
			(stroke
				(width 0.15)
				(type solid)
			)
			(layer "F.SilkS")
		)
		(fp_line
			(start -1 -1.3)
			(end -1 -1.6)
			(stroke
				(width 0.15)
				(type solid)
			)
			(layer "F.SilkS")
		)
		(fp_line
			(start 1 -1.3)
			(end 1 -1.6)
			(stroke
				(width 0.15)
				(type solid)
			)
			(layer "F.SilkS")
		)
		(fp_line
			(start -1 -1.6)
			(end -0.6 -1.6)
			(stroke
				(width 0.15)
				(type solid)
			)
			(layer "F.SilkS")
		)
		(fp_line
			(start 1 -1.6)
			(end 0.625 -1.6)
			(stroke
				(width 0.15)
				(type solid)
			)
			(layer "F.SilkS")
		)
		(fp_circle
			(center -1.3 -1.4)
			(end -1.25 -1.4)
			(stroke
				(width 0.15)
				(type solid)
			)
			(fill yes)
			(layer "F.SilkS")
		)
		(fp_rect
			(start -1.9 -1.75)
			(end 1.898 1.75)
			(stroke
				(width 0.05)
				(type solid)
			)
			(fill no)
			(layer "F.CrtYd")
		)
		(fp_line
			(start -1.4 -1.25)
			(end -1.2 -1.45)
			(stroke
				(width 0.15)
				(type solid)
			)
			(layer "F.Fab")
		)
		(fp_rect
			(start -1.401 -1.45)
			(end 1.398 1.449)
			(stroke
				(width 0.15)
				(type solid)
			)
			(fill no)
			(layer "F.Fab")
		)
		(fp_text user "License: Apache-2.0"
			(at -2.925 6 90)
			(layer "F.Fab")
			(effects
				(font
					(size 0.7 0.7)
					(thickness 0.15)
				)
				(justify right top)
			)
		)
		(fp_text user "${REFERENCE}"
			(at -2.925 4.8 90)
			(layer "F.Fab")
			(effects
				(font
					(size 0.7 0.7)
					(thickness 0.15)
				)
				(justify right top)
			)
		)
		(fp_text user "Author: Antmicro"
			(at -2.925 7.2 90)
			(layer "F.Fab")
			(effects
				(font
					(size 0.7 0.7)
					(thickness 0.15)
				)
				(justify right top)
			)
		)
		(pad "1" smd roundrect
			(at -1.3 -0.975 180)
			(size 0.45 1.1)
			(layers "F.Cu" "F.Mask" "F.Paste")
			(roundrect_rratio 0.25)
			(net 1281 "Net-(U50-IN+)")
			(pinfunction "IN+")
			(pintype "passive")
		)
		(pad "2" smd roundrect
			(at -1.3 -0.325 180)
			(size 0.45 1.1)
			(layers "F.Cu" "F.Mask" "F.Paste")
			(roundrect_rratio 0.25)
			(net 1161 "Net-(U50-IN-)")
			(pinfunction "IN-")
			(pintype "passive")
		)
		(pad "3" smd roundrect
			(at -1.3 0.325 180)
			(size 0.45 1.1)
			(layers "F.Cu" "F.Mask" "F.Paste")
			(roundrect_rratio 0.25)
			(net 1 "GND")
			(pinfunction "GND")
			(pintype "power_in")
		)
		(pad "4" smd roundrect
			(at -1.3 0.975 180)
			(size 0.45 1.1)
			(layers "F.Cu" "F.Mask" "F.Paste")
			(roundrect_rratio 0.25)
			(net 4 "+3V3_AON")
			(pinfunction "V_{S}")
			(pintype "power_in")
		)
		(pad "5" smd roundrect
			(at 1.3 0.975 180)
			(size 0.45 1.1)
			(layers "F.Cu" "F.Mask" "F.Paste")
			(roundrect_rratio 0.25)
			(net 853 "/I2C_{SYS}.SCL")
			(pinfunction "SCL")
			(pintype "open_collector")
		)
		(pad "6" smd roundrect
			(at 1.3 0.325 180)
			(size 0.45 1.1)
			(layers "F.Cu" "F.Mask" "F.Paste")
			(roundrect_rratio 0.25)
			(net 850 "/I2C_{SYS}.SDA")
			(pinfunction "SDA")
			(pintype "open_collector")
		)
		(pad "7" smd roundrect
			(at 1.3 -0.325 180)
			(size 0.45 1.1)
			(layers "F.Cu" "F.Mask" "F.Paste")
			(roundrect_rratio 0.25)
			(net 4 "+3V3_AON")
			(pinfunction "A0")
			(pintype "passive")
		)
		(pad "8" smd roundrect
			(at 1.3 -0.975 180)
			(size 0.45 1.1)
			(layers "F.Cu" "F.Mask" "F.Paste")
			(roundrect_rratio 0.25)
			(net 1 "GND")
			(pinfunction "A1")
			(pintype "passive")
		)
	)
	(footprint "antmicro-footprints:C_0805_2012Metric"
		(layer "F.Cu")
		(at 174.18 110.356 90)
		(descr "Capacitor SMD 0805")
		(tags "capacitor SMD 0805")
		(property "Reference" "C42"
			(at 1.89 0.41 90)
			(layer "F.SilkS")
			(effects
				(font
					(size 0.7 0.7)
					(thickness 0.15)
				)
				(justify left bottom)
			)
		)
		(property "Value" "C_22u_25V_0805"
			(at -2.055717 1.963152 90)
			(layer "F.Fab")
			(effects
				(font
					(size 0.7 0.7)
					(thickness 0.15)
				)
				(justify left bottom)
			)
		)
		(property "Datasheet" "https://product.samsungsem.com/mlcc/CL21A226MAYNNN.do"
			(at 0 0 90)
			(layer "F.Fab")
			(hide yes)
			(effects
				(font
					(size 1.27 1.27)
					(thickness 0.15)
				)
			)
		)
		(property "Description" "SMT Multilayer Ceramic Capacitor, 22uF, +/-20%, 25V, X5R, 0805 [2012 Metric]"
			(at 0 0 90)
			(layer "F.Fab")
			(hide yes)
			(effects
				(font
					(size 1.27 1.27)
					(thickness 0.15)
				)
			)
		)
		(property "MPN" "CL21A226MAYNNNE"
			(at 0 0 90)
			(unlocked yes)
			(layer "F.Fab")
			(hide yes)
			(effects
				(font
					(size 1 1)
					(thickness 0.15)
				)
			)
		)
		(property "Manufacturer" "Samsung Electro-Mechanics"
			(at 0 0 90)
			(unlocked yes)
			(layer "F.Fab")
			(hide yes)
			(effects
				(font
					(size 1 1)
					(thickness 0.15)
				)
			)
		)
		(property "License" "Apache-2.0"
			(at 0 0 90)
			(unlocked yes)
			(layer "F.Fab")
			(hide yes)
			(effects
				(font
					(size 1 1)
					(thickness 0.15)
				)
			)
		)
		(property "Author" "Antmicro"
			(at 0 0 90)
			(unlocked yes)
			(layer "F.Fab")
			(hide yes)
			(effects
				(font
					(size 1 1)
					(thickness 0.15)
				)
			)
		)
		(property "Val" "22u"
			(at 0 0 90)
			(unlocked yes)
			(layer "F.Fab")
			(hide yes)
			(effects
				(font
					(size 1 1)
					(thickness 0.15)
				)
			)
		)
		(property "Voltage" "25V"
			(at 0 0 90)
			(unlocked yes)
			(layer "F.Fab")
			(hide yes)
			(effects
				(font
					(size 1 1)
					(thickness 0.15)
				)
			)
		)
		(property "Dielectric" "X5R"
			(at 0 0 90)
			(unlocked yes)
			(layer "F.Fab")
			(hide yes)
			(effects
				(font
					(size 1 1)
					(thickness 0.15)
				)
			)
		)
		(property "Public" "False"
			(at 0 0 90)
			(unlocked yes)
			(layer "F.Fab")
			(hide yes)
			(effects
				(font
					(size 1 1)
					(thickness 0.15)
				)
			)
		)
		(sheetname "/DCDC/")
		(sheetfile "dcdc.kicad_sch")
		(attr smd)
		(fp_line
			(start -0.3 -0.7)
			(end 0.3 -0.7)
			(stroke
				(width 0.15)
				(type solid)
			)
			(layer "F.SilkS")
		)
		(fp_line
			(start -0.3 0.7)
			(end 0.3 0.7)
			(stroke
				(width 0.15)
				(type solid)
			)
			(layer "F.SilkS")
		)
		(fp_rect
			(start 1.95 -0.9)
			(end -1.95 0.9)
			(stroke
				(width 0.05)
				(type default)
			)
			(fill no)
			(layer "F.CrtYd")
		)
		(fp_rect
			(start -0.95 -0.675)
			(end 0.95 0.675)
			(stroke
				(width 0.15)
				(type solid)
			)
			(fill no)
			(layer "F.Fab")
		)
		(fp_text user "License: Apache-2.0"
			(at -1.9 4.947 90)
			(layer "F.Fab")
			(effects
				(font
					(size 0.7 0.7)
					(thickness 0.15)
				)
				(justify left bottom)
			)
		)
		(fp_text user "${REFERENCE}"
			(at -1.9 3.947 90)
			(layer "F.Fab")
			(effects
				(font
					(size 0.7 0.7)
					(thickness 0.15)
				)
				(justify left bottom)
			)
		)
		(fp_text user "Author: Antmicro"
			(at -1.9 5.947 90)
			(layer "F.Fab")
			(effects
				(font
					(size 0.7 0.7)
					(thickness 0.15)
				)
				(justify left bottom)
			)
		)
		(pad "1" smd roundrect
			(at -1.1 0 90)
			(size 1.2 1.3)
			(layers "F.Cu" "F.Mask" "F.Paste")
			(roundrect_rratio 0.25)
			(net 1 "GND")
			(pintype "passive")
		)
		(pad "2" smd roundrect
			(at 1.1 0 90)
			(size 1.2 1.3)
			(layers "F.Cu" "F.Mask" "F.Paste")
			(roundrect_rratio 0.25)
			(net 13 "VCC")
			(pintype "passive")
		)
	)
	(footprint "antmicro-footprints:C_0402_1005Metric"
		(layer "F.Cu")
		(at 204.75 86.970856 180)
		(descr "Capacitor SMD 0402")
		(tags "capacitor SMD 0402")
		(property "Reference" "C314"
			(at 5.15 -0.429144 180)
			(layer "F.SilkS")
			(effects
				(font
					(size 0.7 0.7)
					(thickness 0.15)
				)
				(justify left bottom)
			)
		)
		(property "Value" "C_100n_0402"
			(at -1.022927 2.155213 180)
			(layer "F.Fab")
			(effects
				(font
					(size 0.7 0.7)
					(thickness 0.15)
				)
				(justify left bottom)
			)
		)
		(property "Datasheet" "https://www.murata.com/products/productdetail?partno=GRM155R61H104KE14%23"
			(at 0 0 180)
			(layer "F.Fab")
			(hide yes)
			(effects
				(font
					(size 1.27 1.27)
					(thickness 0.15)
				)
			)
		)
		(property "Description" "SMD Multilayer Ceramic Capacitor, 0.1 µF, 50 V, 0402 [1005 Metric], ± 10%, X5R, GRM Series"
			(at 0 0 180)
			(layer "F.Fab")
			(hide yes)
			(effects
				(font
					(size 1.27 1.27)
					(thickness 0.15)
				)
			)
		)
		(property "Manufacturer" "Murata"
			(at 0 0 180)
			(unlocked yes)
			(layer "F.Fab")
			(hide yes)
			(effects
				(font
					(size 1 1)
					(thickness 0.15)
				)
			)
		)
		(property "MPN" "GRM155R61H104KE14D"
			(at 0 0 180)
			(unlocked yes)
			(layer "F.Fab")
			(hide yes)
			(effects
				(font
					(size 1 1)
					(thickness 0.15)
				)
			)
		)
		(property "Val" "100n"
			(at 0 0 180)
			(unlocked yes)
			(layer "F.Fab")
			(hide yes)
			(effects
				(font
					(size 1 1)
					(thickness 0.15)
				)
			)
		)
		(property "License" "Apache-2.0"
			(at 0 0 180)
			(unlocked yes)
			(layer "F.Fab")
			(hide yes)
			(effects
				(font
					(size 1 1)
					(thickness 0.15)
				)
			)
		)
		(property "Author" "Antmicro"
			(at 0 0 180)
			(unlocked yes)
			(layer "F.Fab")
			(hide yes)
			(effects
				(font
					(size 1 1)
					(thickness 0.15)
				)
			)
		)
		(property "Voltage" "50V"
			(at 0 0 180)
			(unlocked yes)
			(layer "F.Fab")
			(hide yes)
			(effects
				(font
					(size 1 1)
					(thickness 0.15)
				)
			)
		)
		(property "Dielectric" "X5R"
			(at 0 0 180)
			(unlocked yes)
			(layer "F.Fab")
			(hide yes)
			(effects
				(font
					(size 1 1)
					(thickness 0.15)
				)
			)
		)
		(sheetname "/SoM_IO2/")
		(sheetfile "som_io2.kicad_sch")
		(attr smd)
		(fp_rect
			(start -0.925 -0.47)
			(end 0.925 0.47)
			(stroke
				(width 0.05)
				(type default)
			)
			(fill no)
			(layer "F.CrtYd")
		)
		(fp_line
			(start 0.504 0.248)
			(end -0.494 0.248)
			(stroke
				(width 0.15)
				(type solid)
			)
			(layer "F.Fab")
		)
		(fp_line
			(start 0.504 -0.25)
			(end 0.504 0.248)
			(stroke
				(width 0.15)
				(type solid)
			)
			(layer "F.Fab")
		)
		(fp_line
			(start -0.494 0.248)
			(end -0.494 -0.25)
			(stroke
				(width 0.15)
				(type solid)
			)
			(layer "F.Fab")
		)
		(fp_line
			(start -0.494 -0.25)
			(end 0.504 -0.25)
			(stroke
				(width 0.15)
				(type solid)
			)
			(layer "F.Fab")
		)
		(fp_text user "License: Apache-2.0"
			(at -0.939 5.799 180)
			(layer "F.Fab")
			(effects
				(font
					(size 0.7 0.7)
					(thickness 0.15)
				)
				(justify left bottom)
			)
		)
		(fp_text user "${REFERENCE}"
			(at -0.939 4.599 180)
			(layer "F.Fab")
			(effects
				(font
					(size 0.7 0.7)
					(thickness 0.15)
				)
				(justify left bottom)
			)
		)
		(fp_text user "Author: Antmicro"
			(at -0.939 3.399 180)
			(layer "F.Fab")
			(effects
				(font
					(size 0.7 0.7)
					(thickness 0.15)
				)
				(justify left bottom)
			)
		)
		(pad "1" smd roundrect
			(at -0.48 0 180)
			(size 0.59 0.64)
			(layers "F.Cu" "F.Mask" "F.Paste")
			(roundrect_rratio 0.25)
			(net 583 "/SoM_IO2/DP0.TX0+")
			(pintype "passive")
		)
		(pad "2" smd roundrect
			(at 0.48 0 180)
			(size 0.59 0.64)
			(layers "F.Cu" "F.Mask" "F.Paste")
			(roundrect_rratio 0.25)
			(net 523 "/SoM_IO2/DP0.TX0_C+")
			(pintype "passive")
		)
	)
	(footprint "antmicro-footprints:LED_0603_1608Metric_G"
		(layer "F.Cu")
		(at 235.540532 95.71 180)
		(descr "LED SMD 0603 Green")
		(tags "LED SMD 0603 Green")
		(property "Reference" "D25"
			(at -1.059468 -0.799999 0)
			(layer "F.SilkS")
			(effects
				(font
					(size 0.7 0.7)
					(thickness 0.15)
				)
				(justify right top)
			)
		)
		(property "Value" "LED_G_0603_LTST-C190GKT"
			(at -0.001 1.599 0)
			(layer "F.Fab")
			(effects
				(font
					(size 0.7 0.7)
					(thickness 0.15)
				)
				(justify right top)
			)
		)
		(property "Datasheet" "https://media.digikey.com/pdf/Data%20Sheets/Lite-On%20PDFs/LTST-C190GKT.pdf"
			(at 0 0 0)
			(layer "F.Fab")
			(hide yes)
			(effects
				(font
					(size 1.27 1.27)
					(thickness 0.15)
				)
			)
		)
		(property "Description" "LED, Green, SMD, 0603, 20 mA, 2.1 V, 569 nm"
			(at 0 0 0)
			(layer "F.Fab")
			(hide yes)
			(effects
				(font
					(size 1.27 1.27)
					(thickness 0.15)
				)
			)
		)
		(property "MPN" "LTST-C190GKT"
			(at 0 0 180)
			(unlocked yes)
			(layer "F.Fab")
			(hide yes)
			(effects
				(font
					(size 1 1)
					(thickness 0.15)
				)
			)
		)
		(property "Manufacturer" "Lite-On"
			(at 0 0 180)
			(unlocked yes)
			(layer "F.Fab")
			(hide yes)
			(effects
				(font
					(size 1 1)
					(thickness 0.15)
				)
			)
		)
		(property "Author" "Antmicro"
			(at 0 0 180)
			(unlocked yes)
			(layer "F.Fab")
			(hide yes)
			(effects
				(font
					(size 1 1)
					(thickness 0.15)
				)
			)
		)
		(property "License" "Apache-2.0"
			(at 0 0 180)
			(unlocked yes)
			(layer "F.Fab")
			(hide yes)
			(effects
				(font
					(size 1 1)
					(thickness 0.15)
				)
			)
		)
		(property "Color" "Green"
			(at 0 0 180)
			(unlocked yes)
			(layer "F.Fab")
			(hide yes)
			(effects
				(font
					(size 1 1)
					(thickness 0.15)
				)
			)
		)
		(sheetname "/USB DP Alt mode/")
		(sheetfile "usb_dp.kicad_sch")
		(attr smd)
		(fp_line
			(start 0.22 0.35)
			(end -0.22 0.35)
			(stroke
				(width 0.15)
				(type solid)
			)
			(layer "F.SilkS")
		)
		(fp_line
			(start 0.22 -0.35)
			(end -0.22 -0.35)
			(stroke
				(width 0.15)
				(type solid)
			)
			(layer "F.SilkS")
		)
		(fp_line
			(start 0.105328 0.201008)
			(end 0.105329 -0.198992)
			(stroke
				(width 0.1)
				(type solid)
			)
			(layer "F.SilkS")
		)
		(fp_line
			(start 0.105328 0.201008)
			(end -0.094672 0.001008)
			(stroke
				(width 0.1)
				(type solid)
			)
			(layer "F.SilkS")
		)
		(fp_line
			(start 0.105328 0.001008)
			(end 0.240001 0.001)
			(stroke
				(width 0.1)
				(type solid)
			)
			(layer "F.SilkS")
		)
		(fp_line
			(start -0.094672 0.201008)
			(end -0.094672 -0.198992)
			(stroke
				(width 0.1)
				(type solid)
			)
			(layer "F.SilkS")
		)
		(fp_line
			(start -0.094672 0.001008)
			(end 0.105329 -0.198992)
			(stroke
				(width 0.1)
				(type solid)
			)
			(layer "F.SilkS")
		)
		(fp_line
			(start -0.094672 0.001008)
			(end -0.24 0.001008)
			(stroke
				(width 0.1)
				(type solid)
			)
			(layer "F.SilkS")
		)
		(fp_line
			(start -1.18 -0.319)
			(end -1.18 0.321)
			(stroke
				(width 0.15)
				(type solid)
			)
			(layer "F.SilkS")
		)
		(fp_poly
			(pts
				(xy 1.25 0.65) (xy -1.25 0.65) (xy -1.25 -0.65) (xy 1.25 -0.65)
			)
			(stroke
				(width 0.05)
				(type solid)
			)
			(fill no)
			(layer "F.CrtYd")
		)
		(fp_line
			(start 0.599 0)
			(end 0.200999 0)
			(stroke
				(width 0.15)
				(type solid)
			)
			(layer "F.Fab")
		)
		(fp_line
			(start 0.201 0.2)
			(end 0.200999 0)
			(stroke
				(width 0.15)
				(type solid)
			)
			(layer "F.Fab")
		)
		(fp_line
			(start 0.201 -0.202)
			(end -0.101 0)
			(stroke
				(width 0.15)
				(type solid)
			)
			(layer "F.Fab")
		)
		(fp_line
			(start 0.200999 0)
			(end 0.201 -0.202)
			(stroke
				(width 0.15)
				(type solid)
			)
			(layer "F.Fab")
		)
		(fp_line
			(start -0.101 0)
			(end 0.201 0.2)
			(stroke
				(width 0.15)
				(type solid)
			)
			(layer "F.Fab")
		)
		(fp_line
			(start -0.199 0.2)
			(end -0.199 0.1)
			(stroke
				(width 0.15)
				(type solid)
			)
			(layer "F.Fab")
		)
		(fp_line
			(start -0.199 0)
			(end -0.597 0)
			(stroke
				(width 0.15)
				(type solid)
			)
			(layer "F.Fab")
		)
		(fp_line
			(start -0.199 -0.202)
			(end -0.199 0.1)
			(stroke
				(width 0.15)
				(type solid)
			)
			(layer "F.Fab")
		)
		(fp_poly
			(pts
				(xy 0.848 0.4) (xy -0.85 0.4) (xy -0.85 -0.402) (xy 0.848 -0.401999)
			)
			(stroke
				(width 0.15)
				(type solid)
			)
			(fill no)
			(layer "F.Fab")
		)
		(fp_text user "Author: Antmicro"
			(at -1.4224 4.799 0)
			(layer "F.Fab")
			(effects
				(font
					(size 0.7 0.7)
					(thickness 0.15)
				)
				(justify right top)
			)
		)
		(fp_text user "License: Apache-2.0"
			(at -1.4224 3.599 0)
			(layer "F.Fab")
			(effects
				(font
					(size 0.7 0.7)
					(thickness 0.15)
				)
				(justify right top)
			)
		)
		(fp_text user "${REFERENCE}"
			(at -1.4224 5.999 0)
			(layer "F.Fab")
			(effects
				(font
					(size 0.7 0.7)
					(thickness 0.15)
				)
				(justify right top)
			)
		)
		(pad "1" smd roundrect
			(at -0.7 0)
			(size 0.8 1)
			(layers "F.Cu" "F.Mask" "F.Paste")
			(roundrect_rratio 0.2)
			(net 1 "GND")
			(pinfunction "C")
			(pintype "passive")
		)
		(pad "2" smd roundrect
			(at 0.7 0)
			(size 0.8 1)
			(layers "F.Cu" "F.Mask" "F.Paste")
			(roundrect_rratio 0.2)
			(net 1388 "Net-(D25-A)")
			(pinfunction "A")
			(pintype "passive")
		)
	)
)
